(kicad_pcb
	(version 20260206)
	(generator "pcbnew")
	(generator_version "10.0")
	(general
		(thickness 1.6)
		(legacy_teardrops no)
	)
	(paper "A4")
	(title_block
		(title "pdpb — Lightning_PDPB_BRD.brd")
		(comment 1 "Lightning (Wiwynn / Facebook NVMe JBOF) / footprints 704-709 of 1140")
	)
	(layers
		(0 "F.Cu" signal "TOP")
		(4 "In1.Cu" signal "L2GND")
		(6 "In2.Cu" signal "L3")
		(8 "In3.Cu" signal "L4VCC")
		(10 "In4.Cu" signal "L5VCC")
		(12 "In5.Cu" signal "L6")
		(14 "In6.Cu" signal "L7GND")
		(2 "B.Cu" signal "BOTTOM")
		(9 "F.Adhes" user "F.Adhesive")
		(11 "B.Adhes" user "B.Adhesive")
		(13 "F.Paste" user "Package Geometry/Pastemask Top")
		(15 "B.Paste" user "Package Geometry/Pastemask Bottom")
		(5 "F.SilkS" user "Ref Des/Silkscreen Top")
		(7 "B.SilkS" user "Ref Des/Silkscreen Bottom")
		(1 "F.Mask" user "Board Geometry/Soldermask Top")
		(3 "B.Mask" user "Board Geometry/Soldermask Bottom")
		(17 "Dwgs.User" user "User.Drawings")
		(19 "Cmts.User" user "User.Comments")
		(21 "Eco1.User" user "User.Eco1")
		(23 "Eco2.User" user "User.Eco2")
		(25 "Edge.Cuts" user "Board Geometry/Outline")
		(27 "Margin" user)
		(31 "F.CrtYd" user "Package Geometry/Place Bound Top")
		(29 "B.CrtYd" user "Package Geometry/Place Bound Bottom")
		(35 "F.Fab" user "Ref Des/Assembly Top")
		(33 "B.Fab" user "Ref Des/Assembly Bottom")
	)
	(footprint ""
		(layer "F.Cu")
		(at 31.6992 -491.2614 -90)
		(property "Reference" "R397"
			(at 0 0 270)
			(layer "F.SilkS")
			(hide yes)
			(effects
				(font
					(size 1.27 1.27)
				)
			)
		)
		(property "Value" "0R2J-2-GP"
			(at 0.064008 -3.993896 270)
			(unlocked yes)
			(layer "F.Fab")
			(hide yes)
			(effects
				(font
					(size 1.016 1.016)
					(thickness 0.1524)
				)
			)
		)
		(property "Device Type" "R402H16"
			(at 0.064008 -5.517896 270)
			(unlocked yes)
			(layer "F.Fab")
			(hide yes)
			(effects
				(font
					(size 1.016 1.016)
					(thickness 0.1524)
				)
			)
		)
		(duplicate_pad_numbers_are_jumpers no)
		(fp_line
			(start -0.508 -0.9398)
			(end -0.508 0.9398)
			(stroke
				(width 0.1524)
				(type default)
			)
			(layer "F.SilkS")
		)
		(fp_line
			(start 0.508 -0.9398)
			(end -0.508 -0.9398)
			(stroke
				(width 0.1524)
				(type default)
			)
			(layer "F.SilkS")
		)
		(fp_rect
			(start -0.508 0.9398)
			(end 0.508 -0.9398)
			(stroke
				(width 0)
				(type default)
			)
			(fill no)
			(layer "F.CrtYd")
		)
		(fp_rect
			(start -0.508 0.9398)
			(end 0.508 -0.9398)
			(stroke
				(width 0)
				(type default)
			)
			(fill no)
			(layer "F.Fab")
		)
		(pad "1" smd custom
			(at 0 -0.4445 270)
			(size 0.1397 0.1397)
			(layers "F.Cu" "F.Mask" "F.Paste")
			(net "SCL_DR5_R")
			(options
				(clearance outline)
				(anchor circle)
			)
			(primitives
				(gr_poly
					(pts
						(arc
							(start -0.1778 -0.2794)
							(mid -0.249642 -0.249642)
							(end -0.2794 -0.1778)
						)
						(arc
							(start -0.2794 0.1778)
							(mid -0.249642 0.249642)
							(end -0.1778 0.2794)
						)
						(arc
							(start 0.1778 0.2794)
							(mid 0.249642 0.249642)
							(end 0.2794 0.1778)
						)
						(arc
							(start 0.2794 -0.1778)
							(mid 0.249642 -0.249642)
							(end 0.1778 -0.2794)
						)
					)
					(width 0)
					(fill yes)
				)
			)
		)
		(pad "2" smd custom
			(at 0 0.4445 270)
			(size 0.1397 0.1397)
			(layers "F.Cu" "F.Mask" "F.Paste")
			(net "SCL_DR5")
			(options
				(clearance outline)
				(anchor circle)
			)
			(primitives
				(gr_poly
					(pts
						(arc
							(start -0.1778 -0.2794)
							(mid -0.249642 -0.249642)
							(end -0.2794 -0.1778)
						)
						(arc
							(start -0.2794 0.1778)
							(mid -0.249642 0.249642)
							(end -0.1778 0.2794)
						)
						(arc
							(start 0.1778 0.2794)
							(mid 0.249642 0.249642)
							(end 0.2794 0.1778)
						)
						(arc
							(start 0.2794 -0.1778)
							(mid 0.249642 -0.249642)
							(end 0.1778 -0.2794)
						)
					)
					(width 0)
					(fill yes)
				)
			)
		)
	)
	(footprint ""
		(layer "F.Cu")
		(at 75.8063 -143.256 180)
		(property "Reference" "SR965"
			(at 0 0 180)
			(layer "F.SilkS")
			(hide yes)
			(effects
				(font
					(size 1.27 1.27)
				)
			)
		)
		(property "Value" "2KR2F-3-GP"
			(at 0.064008 -3.993896 180)
			(unlocked yes)
			(layer "F.Fab")
			(hide yes)
			(effects
				(font
					(size 1.016 1.016)
					(thickness 0.1524)
				)
			)
		)
		(property "Device Type" "R402H16"
			(at 0.064008 -5.517896 180)
			(unlocked yes)
			(layer "F.Fab")
			(hide yes)
			(effects
				(font
					(size 1.016 1.016)
					(thickness 0.1524)
				)
			)
		)
		(duplicate_pad_numbers_are_jumpers no)
		(fp_line
			(start 0.508 -0.9398)
			(end -0.508 -0.9398)
			(stroke
				(width 0.1524)
				(type default)
			)
			(layer "F.SilkS")
		)
		(fp_line
			(start -0.508 -0.9398)
			(end -0.508 0.9398)
			(stroke
				(width 0.1524)
				(type default)
			)
			(layer "F.SilkS")
		)
		(fp_rect
			(start -0.508 0.9398)
			(end 0.508 -0.9398)
			(stroke
				(width 0)
				(type default)
			)
			(fill no)
			(layer "F.CrtYd")
		)
		(fp_rect
			(start -0.508 0.9398)
			(end 0.508 -0.9398)
			(stroke
				(width 0)
				(type default)
			)
			(fill no)
			(layer "F.Fab")
		)
		(pad "1" smd custom
			(at 0 -0.4445 180)
			(size 0.1397 0.1397)
			(layers "F.Cu" "F.Mask" "F.Paste")
			(net "P3V3")
			(options
				(clearance outline)
				(anchor circle)
			)
			(primitives
				(gr_poly
					(pts
						(arc
							(start -0.1778 -0.2794)
							(mid -0.249642 -0.249642)
							(end -0.2794 -0.1778)
						)
						(arc
							(start -0.2794 0.1778)
							(mid -0.249642 0.249642)
							(end -0.1778 0.2794)
						)
						(arc
							(start 0.1778 0.2794)
							(mid 0.249642 0.249642)
							(end 0.2794 0.1778)
						)
						(arc
							(start 0.2794 -0.1778)
							(mid 0.249642 -0.249642)
							(end 0.1778 -0.2794)
						)
					)
					(width 0)
					(fill yes)
				)
			)
		)
		(pad "2" smd custom
			(at 0 0.4445 180)
			(size 0.1397 0.1397)
			(layers "F.Cu" "F.Mask" "F.Paste")
			(net "SCL_DR14")
			(options
				(clearance outline)
				(anchor circle)
			)
			(primitives
				(gr_poly
					(pts
						(arc
							(start -0.1778 -0.2794)
							(mid -0.249642 -0.249642)
							(end -0.2794 -0.1778)
						)
						(arc
							(start -0.2794 0.1778)
							(mid -0.249642 0.249642)
							(end -0.1778 0.2794)
						)
						(arc
							(start 0.1778 0.2794)
							(mid 0.249642 0.249642)
							(end 0.2794 0.1778)
						)
						(arc
							(start 0.2794 -0.1778)
							(mid 0.249642 -0.249642)
							(end 0.1778 -0.2794)
						)
					)
					(width 0)
					(fill yes)
				)
			)
		)
	)
	(footprint ""
		(layer "F.Cu")
		(at 76.0984 -366.522)
		(property "Reference" "SR984"
			(at 0 0 0)
			(layer "F.SilkS")
			(hide yes)
			(effects
				(font
					(size 1.27 1.27)
				)
			)
		)
		(property "Value" "2KR2F-3-GP"
			(at 0.064008 -3.993896 0)
			(unlocked yes)
			(layer "F.Fab")
			(hide yes)
			(effects
				(font
					(size 1.016 1.016)
					(thickness 0.1524)
				)
			)
		)
		(property "Device Type" "R402H16"
			(at 0.064008 -5.517896 0)
			(unlocked yes)
			(layer "F.Fab")
			(hide yes)
			(effects
				(font
					(size 1.016 1.016)
					(thickness 0.1524)
				)
			)
		)
		(duplicate_pad_numbers_are_jumpers no)
		(fp_line
			(start -0.508 -0.9398)
			(end -0.508 0.9398)
			(stroke
				(width 0.1524)
				(type default)
			)
			(layer "F.SilkS")
		)
		(fp_line
			(start 0.508 -0.9398)
			(end -0.508 -0.9398)
			(stroke
				(width 0.1524)
				(type default)
			)
			(layer "F.SilkS")
		)
		(fp_rect
			(start -0.508 0.9398)
			(end 0.508 -0.9398)
			(stroke
				(width 0)
				(type default)
			)
			(fill no)
			(layer "F.CrtYd")
		)
		(fp_rect
			(start -0.508 0.9398)
			(end 0.508 -0.9398)
			(stroke
				(width 0)
				(type default)
			)
			(fill no)
			(layer "F.Fab")
		)
		(pad "1" smd custom
			(at 0 -0.4445)
			(size 0.1397 0.1397)
			(layers "F.Cu" "F.Mask" "F.Paste")
			(net "P3V3")
			(options
				(clearance outline)
				(anchor circle)
			)
			(primitives
				(gr_poly
					(pts
						(arc
							(start -0.1778 -0.2794)
							(mid -0.249642 -0.249642)
							(end -0.2794 -0.1778)
						)
						(arc
							(start -0.2794 0.1778)
							(mid -0.249642 0.249642)
							(end -0.1778 0.2794)
						)
						(arc
							(start 0.1778 0.2794)
							(mid 0.249642 0.249642)
							(end 0.2794 0.1778)
						)
						(arc
							(start 0.2794 -0.1778)
							(mid 0.249642 -0.249642)
							(end 0.1778 -0.2794)
						)
					)
					(width 0)
					(fill yes)
				)
			)
		)
		(pad "2" smd custom
			(at 0 0.4445)
			(size 0.1397 0.1397)
			(layers "F.Cu" "F.Mask" "F.Paste")
			(net "SDA_DR10")
			(options
				(clearance outline)
				(anchor circle)
			)
			(primitives
				(gr_poly
					(pts
						(arc
							(start -0.1778 -0.2794)
							(mid -0.249642 -0.249642)
							(end -0.2794 -0.1778)
						)
						(arc
							(start -0.2794 0.1778)
							(mid -0.249642 0.249642)
							(end -0.1778 0.2794)
						)
						(arc
							(start 0.1778 0.2794)
							(mid 0.249642 0.249642)
							(end 0.2794 0.1778)
						)
						(arc
							(start 0.2794 -0.1778)
							(mid 0.249642 -0.249642)
							(end 0.1778 -0.2794)
						)
					)
					(width 0)
					(fill yes)
				)
			)
		)
	)
	(footprint ""
		(layer "F.Cu")
		(at 253.499874 -274.997418)
		(property "Reference" "H5"
			(at 0 0 0)
			(layer "F.SilkS")
			(hide yes)
			(effects
				(font
					(size 1.27 1.27)
				)
			)
		)
		(property "Value" "GEN276X162R197X296-6-F-A-GP"
			(at -6.7183 4.1402 0)
			(unlocked yes)
			(layer "F.Fab")
			(hide yes)
			(effects
				(font
					(size 1.016 1.016)
					(thickness 0.1524)
				)
			)
		)
		(property "Device Type" "GEN276X162R197X296-6-F-A"
			(at -6.7183 2.6162 0)
			(unlocked yes)
			(layer "F.Fab")
			(hide yes)
			(effects
				(font
					(size 1.016 1.016)
					(thickness 0.1524)
				)
			)
		)
		(duplicate_pad_numbers_are_jumpers no)
		(fp_poly
			(pts
				(arc
					(start 2.723642 4.777232)
					(mid -0.000169 6.508462)
					(end -2.723896 4.776978)
				)
				(arc
					(start -2.723896 4.776978)
					(mid 0.000173 -5.499012)
					(end 2.723642 4.777232)
				)
			)
			(stroke
				(width 0)
				(type default)
			)
			(fill no)
			(layer "B.CrtYd")
		)
		(fp_poly
			(pts
				(arc
					(start 2.723642 4.777232)
					(mid -0.000169 6.508462)
					(end -2.723896 4.776978)
				)
				(arc
					(start -2.723896 4.776978)
					(mid 0.000173 -5.499012)
					(end 2.723642 4.777232)
				)
			)
			(stroke
				(width 0)
				(type default)
			)
			(fill no)
			(layer "F.CrtYd")
		)
		(fp_poly
			(pts
				(arc
					(start 2.723642 4.777232)
					(mid -0.000169 6.508462)
					(end -2.723896 4.776978)
				)
				(arc
					(start -2.723896 4.776978)
					(mid 0.000173 -5.499012)
					(end 2.723642 4.777232)
				)
			)
			(stroke
				(width 0)
				(type default)
			)
			(fill no)
			(layer "B.Fab")
		)
		(fp_poly
			(pts
				(arc
					(start 2.723642 4.777232)
					(mid -0.000169 6.508462)
					(end -2.723896 4.776978)
				)
				(arc
					(start -2.723896 4.776978)
					(mid 0.000173 -5.499012)
					(end 2.723642 4.777232)
				)
			)
			(stroke
				(width 0)
				(type default)
			)
			(fill no)
			(layer "F.Fab")
		)
		(pad "" np_thru_hole circle
			(at 0 0)
			(size 0.254 0.254)
			(drill 0.0254)
			(layers "*.Cu" "*.Mask")
			(clearance 3.135376)
			(thermal_gap 3.135376)
		)
		(pad "1" thru_hole circle
			(at 2.549906 0)
			(size 0.8636 0.8636)
			(drill 0.508)
			(layers "*.Cu" "*.Mask")
			(remove_unused_layers no)
			(net "GND")
			(clearance 0.8255)
			(thermal_gap 0.8255)
		)
		(pad "2" thru_hole circle
			(at 2.210054 -1.27)
			(size 0.8636 0.8636)
			(drill 0.508)
			(layers "*.Cu" "*.Mask")
			(remove_unused_layers no)
			(net "GND")
			(clearance 0.8255)
			(thermal_gap 0.8255)
		)
		(pad "3" thru_hole circle
			(at 1.27 -2.210054)
			(size 0.8636 0.8636)
			(drill 0.508)
			(layers "*.Cu" "*.Mask")
			(remove_unused_layers no)
			(net "GND")
			(clearance 0.8255)
			(thermal_gap 0.8255)
		)
		(pad "4" thru_hole circle
			(at -1.279906 -2.210054)
			(size 0.8636 0.8636)
			(drill 0.508)
			(layers "*.Cu" "*.Mask")
			(remove_unused_layers no)
			(net "GND")
			(clearance 0.8255)
			(thermal_gap 0.8255)
		)
		(pad "5" thru_hole circle
			(at -2.210054 -1.27)
			(size 0.8636 0.8636)
			(drill 0.508)
			(layers "*.Cu" "*.Mask")
			(remove_unused_layers no)
			(net "GND")
			(clearance 0.8255)
			(thermal_gap 0.8255)
		)
		(pad "6" thru_hole circle
			(at -2.549906 0)
			(size 0.8636 0.8636)
			(drill 0.508)
			(layers "*.Cu" "*.Mask")
			(remove_unused_layers no)
			(net "GND")
			(clearance 0.8255)
			(thermal_gap 0.8255)
		)
		(zone
			(layers "F.Cu" "B.Cu" "In1.Cu" "In2.Cu" "In3.Cu" "In4.Cu" "In5.Cu" "In6.Cu")
			(hatch none 0.5)
			(connect_pads
				(clearance 0)
			)
			(min_thickness 0.25)
			(keepout
				(tracks allowed)
				(vias not_allowed)
				(pads allowed)
				(copperpour not_allowed)
				(footprints allowed)
			)
			(placement
				(enabled no)
				(sheetname "")
			)
			(fill
				(thermal_gap 0.5)
				(thermal_bridge_width 0.5)
				(island_removal_mode 0)
			)
			(polygon
				(pts
					(arc
						(start 257.817874 -275.000466)
						(mid 249.181874 -275.000466)
						(end 257.817874 -275.000466)
					)
				)
			)
		)
		(zone
			(layers "F.Cu" "B.Cu" "In1.Cu" "In2.Cu" "In3.Cu" "In4.Cu" "In5.Cu" "In6.Cu")
			(hatch none 0.5)
			(connect_pads
				(clearance 0)
			)
			(min_thickness 0.25)
			(keepout
				(tracks not_allowed)
				(vias allowed)
				(pads allowed)
				(copperpour not_allowed)
				(footprints allowed)
			)
			(placement
				(enabled no)
				(sheetname "")
			)
			(fill
				(thermal_gap 0.5)
				(thermal_bridge_width 0.5)
				(island_removal_mode 0)
			)
			(polygon
				(pts
					(arc
						(start 255.839214 -273.388074)
						(mid 253.499954 -268.488971)
						(end 251.16028 -273.388074)
					)
					(arc
						(start 251.16028 -273.388074)
						(mid 251.406247 -273.82844)
						(end 251.491496 -274.325588)
					)
					(arc
						(start 251.491496 -274.997418)
						(mid 253.499874 -277.005796)
						(end 255.507998 -274.997418)
					)
					(arc
						(start 255.507998 -274.325588)
						(mid 255.593233 -273.828434)
						(end 255.839214 -273.388074)
					)
				)
			)
		)
	)
	(footprint ""
		(layer "F.Cu")
		(at 8.8138 -470.6366 90)
		(property "Reference" "PC1166"
			(at 0 0 90)
			(layer "F.SilkS")
			(hide yes)
			(effects
				(font
					(size 1.27 1.27)
				)
			)
		)
		(property "Value" "SC22U25V6KX-GP-U"
			(at -2.860802 -5.279644 90)
			(unlocked yes)
			(layer "F.Fab")
			(hide yes)
			(effects
				(font
					(size 1.016 1.016)
					(thickness 0.1524)
				)
			)
		)
		(property "Device Type" "C1206-TO0D3H75"
			(at -2.860802 -6.803644 90)
			(unlocked yes)
			(layer "F.Fab")
			(hide yes)
			(effects
				(font
					(size 1.016 1.016)
					(thickness 0.1524)
				)
			)
		)
		(duplicate_pad_numbers_are_jumpers no)
		(fp_line
			(start 1.3081 -2.3749)
			(end 1.3081 2.3749)
			(stroke
				(width 0.1524)
				(type default)
			)
			(layer "F.SilkS")
		)
		(fp_line
			(start -1.3081 -2.3749)
			(end 1.3081 -2.3749)
			(stroke
				(width 0.1524)
				(type default)
			)
			(layer "F.SilkS")
		)
		(fp_line
			(start 1.3081 2.3749)
			(end -1.3081 2.3749)
			(stroke
				(width 0.1524)
				(type default)
			)
			(layer "F.SilkS")
		)
		(fp_line
			(start -1.3081 2.3749)
			(end -1.3081 -2.3749)
			(stroke
				(width 0.1524)
				(type default)
			)
			(layer "F.SilkS")
		)
		(fp_rect
			(start -0.8001 1.6002)
			(end 0.8001 -1.6002)
			(stroke
				(width 0)
				(type default)
			)
			(fill no)
			(layer "F.CrtYd")
		)
		(fp_poly
			(pts
				(xy -1.5621 2.4511) (xy -1.5621 1.6002) (xy 0.8001 1.6002) (xy 0.8001 -1.6002) (xy -0.8001 -1.6002)
				(xy -0.8001 1.5875) (xy -1.5621 1.5875) (xy -1.5621 -2.4511) (xy 1.5621 -2.4511) (xy 1.5621 2.4511)
			)
			(stroke
				(width 0)
				(type default)
			)
			(fill no)
			(layer "F.CrtYd")
		)
		(fp_rect
			(start -1.5621 2.4511)
			(end 1.5621 -2.4511)
			(stroke
				(width 0)
				(type default)
			)
			(fill no)
			(layer "F.Fab")
		)
		(pad "1" smd rect
			(at 0 -1.392936 90)
			(size 2.1082 1.4478)
			(layers "F.Cu" "F.Mask" "F.Paste")
			(net "P12V")
		)
		(pad "2" smd rect
			(at 0 1.392936 90)
			(size 2.1082 1.4478)
			(layers "F.Cu" "F.Mask" "F.Paste")
			(net "GND")
		)
	)
	(footprint ""
		(layer "F.Cu")
		(at 7.9248 -450.9389 -90)
		(property "Reference" "C9540"
			(at 0 0 270)
			(layer "F.SilkS")
			(hide yes)
			(effects
				(font
					(size 1.27 1.27)
				)
			)
		)
		(property "Value" "SCD01U50V2KX-1GP"
			(at 1.1811 -2.7051 270)
			(unlocked yes)
			(layer "F.Fab")
			(hide yes)
			(effects
				(font
					(size 1.016 1.016)
					(thickness 0.1524)
				)
			)
		)
		(property "Device Type" "C402H22"
			(at 1.1811 -4.2291 270)
			(unlocked yes)
			(layer "F.Fab")
			(hide yes)
			(effects
				(font
					(size 1.016 1.016)
					(thickness 0.1524)
				)
			)
		)
		(duplicate_pad_numbers_are_jumpers no)
		(fp_rect
			(start -0.4318 0.9525)
			(end 0.4318 -0.9525)
			(stroke
				(width 0)
				(type default)
			)
			(fill no)
			(layer "F.CrtYd")
		)
		(fp_rect
			(start -0.4318 0.9525)
			(end 0.4318 -0.9525)
			(stroke
				(width 0)
				(type default)
			)
			(fill no)
			(layer "F.Fab")
		)
		(pad "1" smd custom
			(at 0 -0.4445 270)
			(size 0.1524 0.1524)
			(layers "F.Cu" "F.Mask" "F.Paste")
			(net "PE_100M_CLK4_P")
			(options
				(clearance outline)
				(anchor circle)
			)
			(primitives
				(gr_poly
					(pts
						(arc
							(start 0.3048 -0.2032)
							(mid 0.275042 -0.275042)
							(end 0.2032 -0.3048)
						)
						(arc
							(start -0.2032 -0.3048)
							(mid -0.275042 -0.275042)
							(end -0.3048 -0.2032)
						)
						(arc
							(start -0.3048 0.2032)
							(mid -0.275042 0.275042)
							(end -0.2032 0.3048)
						)
						(arc
							(start 0.2032 0.3048)
							(mid 0.275042 0.275042)
							(end 0.3048 0.2032)
						)
					)
					(width 0)
					(fill yes)
				)
			)
		)
		(pad "2" smd custom
			(at 0 0.4445 270)
			(size 0.1524 0.1524)
			(layers "F.Cu" "F.Mask" "F.Paste")
			(net "PE_100M_CLK4_C_P")
			(options
				(clearance outline)
				(anchor circle)
			)
			(primitives
				(gr_poly
					(pts
						(arc
							(start 0.3048 -0.2032)
							(mid 0.275042 -0.275042)
							(end 0.2032 -0.3048)
						)
						(arc
							(start -0.2032 -0.3048)
							(mid -0.275042 -0.275042)
							(end -0.3048 -0.2032)
						)
						(arc
							(start -0.3048 0.2032)
							(mid -0.275042 0.275042)
							(end -0.2032 0.3048)
						)
						(arc
							(start 0.2032 0.3048)
							(mid 0.275042 0.275042)
							(end 0.3048 0.2032)
						)
					)
					(width 0)
					(fill yes)
				)
			)
		)
	)
)
